# BASEBOARD_FAB2 (Tioga Pass) — schematic netlist excerpt (pin names and nets, part order shuffled) for the footprints in the layout excerpt that follows; sources: Cadence DE-HDL packaged netlist, KiCad conversion of Wiwynn_Tioga_Pass_MB.brd

R3P34  RES  0.0 5% CHIP  pkg 0402  page 190 : A = RST_CPU0_LVC3_R1_N ; B = RST_CPU0_LVC3_N
R9U4  RES  49.9 1% CHIP  pkg 0402  page 223 : A = PVCCIO_CPU1 ; B = SVID_CLK1_CPU1_R

(kicad_pcb
	(version 20260206)
	(generator "pcbnew")
	(generator_version "10.0")
	(general
		(thickness 1.6)
		(legacy_teardrops no)
	)
	(paper "A4")
	(title_block
		(title "Wiwynn_Tioga_Pass_MB.brd")
		(comment 1 "Tioga Pass / footprints 4769-4770 of 4770")
	)
	(layers
		(0 "F.Cu" signal "TOP")
		(4 "In1.Cu" signal "L2GND")
		(6 "In2.Cu" signal "L3")
		(8 "In3.Cu" signal "L4GND")
		(10 "In4.Cu" signal "L5")
		(12 "In5.Cu" signal "L6GND")
		(14 "In6.Cu" signal "L7VCC")
		(16 "In7.Cu" signal "L8VCC")
		(18 "In8.Cu" signal "L9GND")
		(20 "In9.Cu" signal "L10")
		(22 "In10.Cu" signal "L11GND")
		(24 "In11.Cu" signal "L12")
		(26 "In12.Cu" signal "L13GND")
		(2 "B.Cu" signal "BOTTOM")
		(9 "F.Adhes" user "F.Adhesive")
		(11 "B.Adhes" user "B.Adhesive")
		(13 "F.Paste" user "Package Geometry/Pastemask Top")
		(15 "B.Paste" user "Package Geometry/Pastemask Bottom")
		(5 "F.SilkS" user "Ref Des/Silkscreen Top")
		(7 "B.SilkS" user "Ref Des/Silkscreen Bottom")
		(1 "F.Mask" user "Board Geometry/Soldermask Top")
		(3 "B.Mask" user "Board Geometry/Soldermask Bottom")
		(17 "Dwgs.User" user "User.Drawings")
		(19 "Cmts.User" user "User.Comments")
		(21 "Eco1.User" user "User.Eco1")
		(23 "Eco2.User" user "User.Eco2")
		(25 "Edge.Cuts" user "Board Geometry/Outline")
		(27 "Margin" user)
		(31 "F.CrtYd" user "Package Geometry/Place Bound Top")
		(29 "B.CrtYd" user "Package Geometry/Place Bound Bottom")
		(35 "F.Fab" user "Ref Des/Assembly Top")
		(33 "B.Fab" user "Ref Des/Assembly Bottom")
	)
	(footprint ""
		(layer "B.Cu")
		(at 11.313668 -3.321812 180)
		(property "Reference" "R9U4"
			(at 0 0 0)
			(layer "B.SilkS")
			(hide yes)
			(effects
				(font
					(size 1.27 1.27)
				)
				(justify mirror)
			)
		)
		(property "Value" ""
			(at 0 0 0)
			(layer "B.Fab")
			(effects
				(font
					(size 1.27 1.27)
				)
				(justify mirror)
			)
		)
		(duplicate_pad_numbers_are_jumpers no)
		(fp_rect
			(start 0.2794 0.9906)
			(end -0.2794 -0.1016)
			(stroke
				(width 0)
				(type default)
			)
			(fill no)
			(layer "B.CrtYd")
		)
		(fp_line
			(start 0.2794 0.9906)
			(end -0.2794 0.9906)
			(stroke
				(width 0.1)
				(type default)
			)
			(layer "B.Fab")
		)
		(fp_line
			(start 0.2794 -0.1016)
			(end 0.2794 0.9906)
			(stroke
				(width 0.1)
				(type default)
			)
			(layer "B.Fab")
		)
		(fp_line
			(start -0.2794 0.9906)
			(end -0.2794 -0.1016)
			(stroke
				(width 0.1)
				(type default)
			)
			(layer "B.Fab")
		)
		(fp_line
			(start -0.2794 -0.1016)
			(end 0.2794 -0.1016)
			(stroke
				(width 0.1)
				(type default)
			)
			(layer "B.Fab")
		)
		(pad "1" smd rect
			(at 0 0)
			(size 0.508 0.508)
			(layers "B.Cu" "B.Mask" "B.Paste")
			(net "PVCCIO_CPU1")
		)
		(pad "2" smd rect
			(at 0 0.889)
			(size 0.508 0.508)
			(layers "B.Cu" "B.Mask" "B.Paste")
			(net "SVID_CLK1_CPU1_R")
		)
		(zone
			(layer "B.Cu")
			(hatch none 0.5)
			(connect_pads
				(clearance 0)
			)
			(min_thickness 0.25)
			(keepout
				(tracks not_allowed)
				(vias allowed)
				(pads allowed)
				(copperpour not_allowed)
				(footprints allowed)
			)
			(placement
				(enabled no)
				(sheetname "")
			)
			(fill
				(thermal_gap 0.5)
				(thermal_bridge_width 0.5)
				(island_removal_mode 0)
			)
			(polygon
				(pts
					(xy 11.059668 -3.956812) (xy 11.059668 -3.575812) (xy 11.567668 -3.575812) (xy 11.567668 -3.956812)
				)
			)
		)
		(zone
			(layer "B.Cu")
			(hatch none 0.5)
			(connect_pads
				(clearance 0)
			)
			(min_thickness 0.25)
			(keepout
				(tracks allowed)
				(vias not_allowed)
				(pads allowed)
				(copperpour not_allowed)
				(footprints allowed)
			)
			(placement
				(enabled no)
				(sheetname "")
			)
			(fill
				(thermal_gap 0.5)
				(thermal_bridge_width 0.5)
				(island_removal_mode 0)
			)
			(polygon
				(pts
					(xy 11.059668 -3.956812) (xy 11.059668 -3.575812) (xy 11.567668 -3.575812) (xy 11.567668 -3.956812)
				)
			)
		)
	)
	(footprint ""
		(layer "B.Cu")
		(at 365.3028 -80.0354 -90)
		(property "Reference" "R3P34"
			(at 0 0 90)
			(layer "B.SilkS")
			(hide yes)
			(effects
				(font
					(size 1.27 1.27)
				)
				(justify mirror)
			)
		)
		(property "Value" ""
			(at 0 0 90)
			(layer "B.Fab")
			(effects
				(font
					(size 1.27 1.27)
				)
				(justify mirror)
			)
		)
		(duplicate_pad_numbers_are_jumpers no)
		(fp_poly
			(pts
				(xy 0.2794 -0.1016) (xy -0.2794 -0.1016) (xy -0.2794 0.9906) (xy 0.2794 0.9906)
			)
			(stroke
				(width 0)
				(type default)
			)
			(fill no)
			(layer "B.CrtYd")
		)
		(fp_line
			(start -0.2794 0.9906)
			(end -0.2794 -0.1016)
			(stroke
				(width 0.1)
				(type default)
			)
			(layer "B.Fab")
		)
		(fp_line
			(start 0.2794 0.9906)
			(end -0.2794 0.9906)
			(stroke
				(width 0.1)
				(type default)
			)
			(layer "B.Fab")
		)
		(fp_line
			(start -0.2794 -0.1016)
			(end 0.2794 -0.1016)
			(stroke
				(width 0.1)
				(type default)
			)
			(layer "B.Fab")
		)
		(fp_line
			(start 0.2794 -0.1016)
			(end 0.2794 0.9906)
			(stroke
				(width 0.1)
				(type default)
			)
			(layer "B.Fab")
		)
		(pad "1" smd rect
			(at 0 0 90)
			(size 0.508 0.508)
			(layers "B.Cu" "B.Mask" "B.Paste")
			(net "RST_CPU0_LVC3_R1_N")
		)
		(pad "2" smd rect
			(at 0 0.889 90)
			(size 0.508 0.508)
			(layers "B.Cu" "B.Mask" "B.Paste")
			(net "RST_CPU0_LVC3_N")
		)
		(zone
			(layer "B.Cu")
			(hatch none 0.5)
			(connect_pads
				(clearance 0)
			)
			(min_thickness 0.25)
			(keepout
				(tracks not_allowed)
				(vias allowed)
				(pads allowed)
				(copperpour not_allowed)
				(footprints allowed)
			)
			(placement
				(enabled no)
				(sheetname "")
			)
			(fill
				(thermal_gap 0.5)
				(thermal_bridge_width 0.5)
				(island_removal_mode 0)
			)
			(polygon
				(pts
					(xy 364.6678 -79.7814) (xy 364.6678 -80.2894) (xy 365.0488 -80.2894) (xy 365.0488 -79.7814)
				)
			)
		)
		(zone
			(layer "B.Cu")
			(hatch none 0.5)
			(connect_pads
				(clearance 0)
			)
			(min_thickness 0.25)
			(keepout
				(tracks allowed)
				(vias not_allowed)
				(pads allowed)
				(copperpour not_allowed)
				(footprints allowed)
			)
			(placement
				(enabled no)
				(sheetname "")
			)
			(fill
				(thermal_gap 0.5)
				(thermal_bridge_width 0.5)
				(island_removal_mode 0)
			)
			(polygon
				(pts
					(xy 365.0488 -79.7814) (xy 365.0488 -80.2894) (xy 364.6678 -80.2894) (xy 364.6678 -79.7814)
				)
			)
		)
	)
)
